(kicad_pcb
	(version 20241229)
	(generator "pcbnew")
	(generator_version "9.0")
	(general
		(thickness 1.599998)
		(legacy_teardrops no)
	)
	(paper "A4")
	(title_block
		(title "Artix - Datacenter Secure Control Module (DC-SCM)")
		(date "2024-11-06")
		(rev "1.1.3")
		(comment 9 "footprints 463-467 of 544")
	)
	(layers
		(0 "F.Cu" signal)
		(4 "In1.Cu" signal)
		(6 "In2.Cu" signal)
		(8 "In3.Cu" signal)
		(10 "In4.Cu" signal)
		(12 "In5.Cu" signal)
		(14 "In6.Cu" signal)
		(2 "B.Cu" signal)
		(9 "F.Adhes" user "F.Adhesive")
		(11 "B.Adhes" user "B.Adhesive")
		(13 "F.Paste" user)
		(15 "B.Paste" user)
		(5 "F.SilkS" user "F.Silkscreen")
		(7 "B.SilkS" user "B.Silkscreen")
		(1 "F.Mask" user)
		(3 "B.Mask" user)
		(17 "Dwgs.User" user "User.Drawings")
		(19 "Cmts.User" user "User.Comments")
		(21 "Eco1.User" user "User.Eco1")
		(23 "Eco2.User" user "User.Eco2")
		(25 "Edge.Cuts" user)
		(27 "Margin" user)
		(31 "F.CrtYd" user "F.Courtyard")
		(29 "B.CrtYd" user "B.Courtyard")
		(35 "F.Fab" user)
		(33 "B.Fab" user)
	)
	(footprint "antmicro-footprints:C_0201"
		(layer "B.Cu")
		(at 104.325 123.625)
		(descr "Capacitor SMD 0201")
		(tags "capacitor SMD 0201")
		(property "Reference" "C171"
			(at 8.175 0.475 0)
			(layer "B.SilkS")
			(effects
				(font
					(size 0.7 0.7)
					(thickness 0.15)
				)
				(justify right bottom mirror)
			)
		)
		(property "Value" "C_470n_0201"
			(at 0 -1.4 0)
			(layer "B.Fab")
			(effects
				(font
					(size 0.7 0.7)
					(thickness 0.15)
				)
				(justify right bottom mirror)
			)
		)
		(property "Datasheet" "https://product.tdk.com/en/search/capacitor/ceramic/mlcc/info?part_no=C0603X5R1A474M030BC"
			(at 0 0 0)
			(layer "F.Fab")
			(hide yes)
			(effects
				(font
					(size 1.27 1.27)
					(thickness 0.15)
				)
			)
		)
		(property "Description" "SMD Multilayer Ceramic Capacitor, 0.47 µF, 10 V, 0201 [0603 Metric], ± 20%, X5R, C"
			(at 0 0 0)
			(layer "F.Fab")
			(hide yes)
			(effects
				(font
					(size 1.27 1.27)
					(thickness 0.15)
				)
			)
		)
		(property "Author" "Antmicro"
			(at 0 0 0)
			(layer "B.Fab")
			(hide yes)
			(effects
				(font
					(size 1 1)
					(thickness 0.15)
				)
				(justify mirror)
			)
		)
		(property "Dielectric" ""
			(at 0 0 0)
			(layer "B.Fab")
			(hide yes)
			(effects
				(font
					(size 1 1)
					(thickness 0.15)
				)
				(justify mirror)
			)
		)
		(property "License" "Apache-2.0"
			(at 0 0 0)
			(layer "B.Fab")
			(hide yes)
			(effects
				(font
					(size 1 1)
					(thickness 0.15)
				)
				(justify mirror)
			)
		)
		(property "MPN" "C0603X5R1A474M030BC"
			(at 0 0 0)
			(layer "B.Fab")
			(hide yes)
			(effects
				(font
					(size 1 1)
					(thickness 0.15)
				)
				(justify mirror)
			)
		)
		(property "Manufacturer" "TDK"
			(at 0 0 0)
			(layer "B.Fab")
			(hide yes)
			(effects
				(font
					(size 1 1)
					(thickness 0.15)
				)
				(justify mirror)
			)
		)
		(property "Public" "False"
			(at 0 0 0)
			(layer "B.Fab")
			(hide yes)
			(effects
				(font
					(size 1 1)
					(thickness 0.15)
				)
				(justify mirror)
			)
		)
		(property "Val" "470n"
			(at 0 0 0)
			(layer "B.Fab")
			(hide yes)
			(effects
				(font
					(size 1 1)
					(thickness 0.15)
				)
				(justify mirror)
			)
		)
		(property "Voltage" ""
			(at 0 0 0)
			(layer "B.Fab")
			(hide yes)
			(effects
				(font
					(size 1 1)
					(thickness 0.15)
				)
				(justify mirror)
			)
		)
		(property "DNP" ""
			(at 0 0 0)
			(unlocked yes)
			(layer "B.Fab")
			(hide yes)
			(effects
				(font
					(size 1 1)
					(thickness 0.15)
				)
				(justify mirror)
			)
		)
		(sheetname "/FPGA power supply/")
		(sheetfile "fpga-power-supply.kicad_sch")
		(attr smd)
		(fp_rect
			(start -0.7 0.35)
			(end 0.7 -0.35)
			(stroke
				(width 0.05)
				(type default)
			)
			(fill no)
			(layer "B.CrtYd")
		)
		(fp_rect
			(start 0.3 -0.15)
			(end -0.301 0.149)
			(stroke
				(width 0.15)
				(type solid)
			)
			(fill no)
			(layer "B.Fab")
		)
		(pad "" smd roundrect
			(at -0.349 0.002)
			(size 0.318 0.36)
			(layers "B.Paste")
			(roundrect_rratio 0.25)
		)
		(pad "" smd roundrect
			(at 0.341 0.002)
			(size 0.318 0.36)
			(layers "B.Paste")
			(roundrect_rratio 0.25)
		)
		(pad "1" smd roundrect
			(at -0.321 0.002)
			(size 0.46 0.4)
			(layers "B.Cu" "B.Mask")
			(roundrect_rratio 0.25)
			(net 1 "GND")
			(pintype "passive")
		)
		(pad "2" smd roundrect
			(at 0.32 0.002)
			(size 0.46 0.4)
			(layers "B.Cu" "B.Mask")
			(roundrect_rratio 0.25)
			(net 6 "VCC1V0")
			(pintype "passive")
		)
	)
	(footprint "antmicro-footprints:C_0201"
		(layer "B.Cu")
		(at 98.275 120.675)
		(descr "Capacitor SMD 0201")
		(tags "capacitor SMD 0201")
		(property "Reference" "C159"
			(at -22.375 0.625 0)
			(layer "B.SilkS")
			(effects
				(font
					(size 0.7 0.7)
					(thickness 0.15)
				)
				(justify right bottom mirror)
			)
		)
		(property "Value" "C_470n_0201"
			(at 0 -1.4 0)
			(layer "B.Fab")
			(effects
				(font
					(size 0.7 0.7)
					(thickness 0.15)
				)
				(justify right bottom mirror)
			)
		)
		(property "Datasheet" "https://product.tdk.com/en/search/capacitor/ceramic/mlcc/info?part_no=C0603X5R1A474M030BC"
			(at 0 0 0)
			(layer "F.Fab")
			(hide yes)
			(effects
				(font
					(size 1.27 1.27)
					(thickness 0.15)
				)
			)
		)
		(property "Description" "SMD Multilayer Ceramic Capacitor, 0.47 µF, 10 V, 0201 [0603 Metric], ± 20%, X5R, C"
			(at 0 0 0)
			(layer "F.Fab")
			(hide yes)
			(effects
				(font
					(size 1.27 1.27)
					(thickness 0.15)
				)
			)
		)
		(property "Author" "Antmicro"
			(at 0 0 0)
			(layer "B.Fab")
			(hide yes)
			(effects
				(font
					(size 1 1)
					(thickness 0.15)
				)
				(justify mirror)
			)
		)
		(property "Dielectric" ""
			(at 0 0 0)
			(layer "B.Fab")
			(hide yes)
			(effects
				(font
					(size 1 1)
					(thickness 0.15)
				)
				(justify mirror)
			)
		)
		(property "License" "Apache-2.0"
			(at 0 0 0)
			(layer "B.Fab")
			(hide yes)
			(effects
				(font
					(size 1 1)
					(thickness 0.15)
				)
				(justify mirror)
			)
		)
		(property "MPN" "C0603X5R1A474M030BC"
			(at 0 0 0)
			(layer "B.Fab")
			(hide yes)
			(effects
				(font
					(size 1 1)
					(thickness 0.15)
				)
				(justify mirror)
			)
		)
		(property "Manufacturer" "TDK"
			(at 0 0 0)
			(layer "B.Fab")
			(hide yes)
			(effects
				(font
					(size 1 1)
					(thickness 0.15)
				)
				(justify mirror)
			)
		)
		(property "Public" "False"
			(at 0 0 0)
			(layer "B.Fab")
			(hide yes)
			(effects
				(font
					(size 1 1)
					(thickness 0.15)
				)
				(justify mirror)
			)
		)
		(property "Val" "470n"
			(at 0 0 0)
			(layer "B.Fab")
			(hide yes)
			(effects
				(font
					(size 1 1)
					(thickness 0.15)
				)
				(justify mirror)
			)
		)
		(property "Voltage" ""
			(at 0 0 0)
			(layer "B.Fab")
			(hide yes)
			(effects
				(font
					(size 1 1)
					(thickness 0.15)
				)
				(justify mirror)
			)
		)
		(property "DNP" ""
			(at 0 0 0)
			(unlocked yes)
			(layer "B.Fab")
			(hide yes)
			(effects
				(font
					(size 1 1)
					(thickness 0.15)
				)
				(justify mirror)
			)
		)
		(sheetname "/FPGA power supply/")
		(sheetfile "fpga-power-supply.kicad_sch")
		(attr smd)
		(fp_rect
			(start -0.7 0.35)
			(end 0.7 -0.35)
			(stroke
				(width 0.05)
				(type default)
			)
			(fill no)
			(layer "B.CrtYd")
		)
		(fp_rect
			(start 0.3 -0.15)
			(end -0.301 0.149)
			(stroke
				(width 0.15)
				(type solid)
			)
			(fill no)
			(layer "B.Fab")
		)
		(pad "" smd roundrect
			(at -0.349 0.002)
			(size 0.318 0.36)
			(layers "B.Paste")
			(roundrect_rratio 0.25)
		)
		(pad "" smd roundrect
			(at 0.341 0.002)
			(size 0.318 0.36)
			(layers "B.Paste")
			(roundrect_rratio 0.25)
		)
		(pad "1" smd roundrect
			(at -0.321 0.002)
			(size 0.46 0.4)
			(layers "B.Cu" "B.Mask")
			(roundrect_rratio 0.25)
			(net 1 "GND")
			(pintype "passive")
		)
		(pad "2" smd roundrect
			(at 0.32 0.002)
			(size 0.46 0.4)
			(layers "B.Cu" "B.Mask")
			(roundrect_rratio 0.25)
			(net 6 "VCC1V0")
			(pintype "passive")
		)
	)
	(footprint "antmicro-footprints:C_0402_1005Metric"
		(layer "B.Cu")
		(at 109.375 110.275 -90)
		(descr "Capacitor SMD 0402")
		(tags "capacitor SMD 0402")
		(property "Reference" "C235"
			(at -1.475 -1.225 90)
			(layer "B.SilkS")
			(effects
				(font
					(size 0.7 0.7)
					(thickness 0.15)
				)
				(justify left bottom mirror)
			)
		)
		(property "Value" "C_470n_0402"
			(at 0 -1.4 90)
			(layer "B.Fab")
			(effects
				(font
					(size 0.7 0.7)
					(thickness 0.15)
				)
				(justify left bottom mirror)
			)
		)
		(property "Datasheet" "https://product.tdk.com/en/search/capacitor/ceramic/mlcc/info?part_no=C1005X5R1E474M050BB"
			(at 0 0 270)
			(layer "F.Fab")
			(hide yes)
			(effects
				(font
					(size 1.27 1.27)
					(thickness 0.15)
				)
			)
		)
		(property "Description" "SMD Multilayer Ceramic Capacitor, 0.47 µF, 25 V, 0402 [1005 Metric], ± 20%, X5R, C"
			(at 0 0 270)
			(layer "F.Fab")
			(hide yes)
			(effects
				(font
					(size 1.27 1.27)
					(thickness 0.15)
				)
			)
		)
		(property "Author" "Antmicro"
			(at -0.9 219.65 0)
			(layer "B.Fab")
			(hide yes)
			(effects
				(font
					(size 1 1)
					(thickness 0.15)
				)
				(justify mirror)
			)
		)
		(property "Dielectric" ""
			(at -0.9 219.65 0)
			(layer "B.Fab")
			(hide yes)
			(effects
				(font
					(size 1 1)
					(thickness 0.15)
				)
				(justify mirror)
			)
		)
		(property "License" "Apache-2.0"
			(at -0.9 219.65 0)
			(layer "B.Fab")
			(hide yes)
			(effects
				(font
					(size 1 1)
					(thickness 0.15)
				)
				(justify mirror)
			)
		)
		(property "MPN" "C1005X5R1E474M050BB"
			(at -0.9 219.65 0)
			(layer "B.Fab")
			(hide yes)
			(effects
				(font
					(size 1 1)
					(thickness 0.15)
				)
				(justify mirror)
			)
		)
		(property "Manufacturer" "TDK"
			(at -0.9 219.65 0)
			(layer "B.Fab")
			(hide yes)
			(effects
				(font
					(size 1 1)
					(thickness 0.15)
				)
				(justify mirror)
			)
		)
		(property "Val" "470n"
			(at -0.9 219.65 0)
			(layer "B.Fab")
			(hide yes)
			(effects
				(font
					(size 1 1)
					(thickness 0.15)
				)
				(justify mirror)
			)
		)
		(property "Voltage" ""
			(at -0.9 219.65 0)
			(layer "B.Fab")
			(hide yes)
			(effects
				(font
					(size 1 1)
					(thickness 0.15)
				)
				(justify mirror)
			)
		)
		(property "DNP" ""
			(at 0 0 270)
			(unlocked yes)
			(layer "B.Fab")
			(hide yes)
			(effects
				(font
					(size 1 1)
					(thickness 0.15)
				)
				(justify mirror)
			)
		)
		(sheetname "/FPGA banks 13-16/")
		(sheetfile "fpga-banks-13-16.kicad_sch")
		(attr smd)
		(fp_rect
			(start -0.925 0.47)
			(end 0.925 -0.47)
			(stroke
				(width 0.05)
				(type default)
			)
			(fill no)
			(layer "B.CrtYd")
		)
		(fp_line
			(start -0.494 0.25)
			(end 0.504 0.25)
			(stroke
				(width 0.15)
				(type solid)
			)
			(layer "B.Fab")
		)
		(fp_line
			(start 0.504 0.25)
			(end 0.504 -0.248)
			(stroke
				(width 0.15)
				(type solid)
			)
			(layer "B.Fab")
		)
		(fp_line
			(start -0.494 -0.248)
			(end -0.494 0.25)
			(stroke
				(width 0.15)
				(type solid)
			)
			(layer "B.Fab")
		)
		(fp_line
			(start 0.504 -0.248)
			(end -0.494 -0.248)
			(stroke
				(width 0.15)
				(type solid)
			)
			(layer "B.Fab")
		)
		(pad "1" smd roundrect
			(at -0.48 0 270)
			(size 0.59 0.64)
			(layers "B.Cu" "B.Mask" "B.Paste")
			(roundrect_rratio 0.25)
			(net 1 "GND")
			(pintype "passive")
		)
		(pad "2" smd roundrect
			(at 0.48 0 270)
			(size 0.59 0.64)
			(layers "B.Cu" "B.Mask" "B.Paste")
			(roundrect_rratio 0.25)
			(net 2 "VCC3V3")
			(pintype "passive")
		)
	)
	(footprint "antmicro-footprints:C_0402_1005Metric"
		(layer "B.Cu")
		(at 103.175 113.075)
		(descr "Capacitor SMD 0402")
		(tags "capacitor SMD 0402")
		(property "Reference" "C236"
			(at -1.475 -0.475 0)
			(layer "B.SilkS")
			(effects
				(font
					(size 0.7 0.7)
					(thickness 0.15)
				)
				(justify right bottom mirror)
			)
		)
		(property "Value" "C_470n_0402"
			(at 0 -1.4 0)
			(layer "B.Fab")
			(effects
				(font
					(size 0.7 0.7)
					(thickness 0.15)
				)
				(justify right bottom mirror)
			)
		)
		(property "Datasheet" "https://product.tdk.com/en/search/capacitor/ceramic/mlcc/info?part_no=C1005X5R1E474M050BB"
			(at 0 0 0)
			(layer "F.Fab")
			(hide yes)
			(effects
				(font
					(size 1.27 1.27)
					(thickness 0.15)
				)
			)
		)
		(property "Description" "SMD Multilayer Ceramic Capacitor, 0.47 µF, 25 V, 0402 [1005 Metric], ± 20%, X5R, C"
			(at 0 0 0)
			(layer "F.Fab")
			(hide yes)
			(effects
				(font
					(size 1.27 1.27)
					(thickness 0.15)
				)
			)
		)
		(property "Author" "Antmicro"
			(at 0 0 0)
			(layer "B.Fab")
			(hide yes)
			(effects
				(font
					(size 1 1)
					(thickness 0.15)
				)
				(justify mirror)
			)
		)
		(property "Dielectric" ""
			(at 0 0 0)
			(layer "B.Fab")
			(hide yes)
			(effects
				(font
					(size 1 1)
					(thickness 0.15)
				)
				(justify mirror)
			)
		)
		(property "License" "Apache-2.0"
			(at 0 0 0)
			(layer "B.Fab")
			(hide yes)
			(effects
				(font
					(size 1 1)
					(thickness 0.15)
				)
				(justify mirror)
			)
		)
		(property "MPN" "C1005X5R1E474M050BB"
			(at 0 0 0)
			(layer "B.Fab")
			(hide yes)
			(effects
				(font
					(size 1 1)
					(thickness 0.15)
				)
				(justify mirror)
			)
		)
		(property "Manufacturer" "TDK"
			(at 0 0 0)
			(layer "B.Fab")
			(hide yes)
			(effects
				(font
					(size 1 1)
					(thickness 0.15)
				)
				(justify mirror)
			)
		)
		(property "Val" "470n"
			(at 0 0 0)
			(layer "B.Fab")
			(hide yes)
			(effects
				(font
					(size 1 1)
					(thickness 0.15)
				)
				(justify mirror)
			)
		)
		(property "Voltage" ""
			(at 0 0 0)
			(layer "B.Fab")
			(hide yes)
			(effects
				(font
					(size 1 1)
					(thickness 0.15)
				)
				(justify mirror)
			)
		)
		(property "DNP" ""
			(at 0 0 0)
			(unlocked yes)
			(layer "B.Fab")
			(hide yes)
			(effects
				(font
					(size 1 1)
					(thickness 0.15)
				)
				(justify mirror)
			)
		)
		(sheetname "/FPGA banks 13-16/")
		(sheetfile "fpga-banks-13-16.kicad_sch")
		(attr smd)
		(fp_rect
			(start -0.925 0.47)
			(end 0.925 -0.47)
			(stroke
				(width 0.05)
				(type default)
			)
			(fill no)
			(layer "B.CrtYd")
		)
		(fp_line
			(start -0.494 -0.248)
			(end -0.494 0.25)
			(stroke
				(width 0.15)
				(type solid)
			)
			(layer "B.Fab")
		)
		(fp_line
			(start -0.494 0.25)
			(end 0.504 0.25)
			(stroke
				(width 0.15)
				(type solid)
			)
			(layer "B.Fab")
		)
		(fp_line
			(start 0.504 -0.248)
			(end -0.494 -0.248)
			(stroke
				(width 0.15)
				(type solid)
			)
			(layer "B.Fab")
		)
		(fp_line
			(start 0.504 0.25)
			(end 0.504 -0.248)
			(stroke
				(width 0.15)
				(type solid)
			)
			(layer "B.Fab")
		)
		(pad "1" smd roundrect
			(at -0.48 0)
			(size 0.59 0.64)
			(layers "B.Cu" "B.Mask" "B.Paste")
			(roundrect_rratio 0.25)
			(net 1 "GND")
			(pintype "passive")
		)
		(pad "2" smd roundrect
			(at 0.48 0)
			(size 0.59 0.64)
			(layers "B.Cu" "B.Mask" "B.Paste")
			(roundrect_rratio 0.25)
			(net 2 "VCC3V3")
			(pintype "passive")
		)
	)
	(footprint "antmicro-footprints:SC70-3"
		(layer "B.Cu")
		(at 81.575 82.075 180)
		(property "Reference" "Q1"
			(at 0.775 -1.325 0)
			(layer "B.SilkS")
			(effects
				(font
					(size 0.7 0.7)
					(thickness 0.15)
				)
				(justify left bottom mirror)
			)
		)
		(property "Value" "BSS138PW"
			(at 0 -2.3 0)
			(layer "B.Fab")
			(effects
				(font
					(size 0.7 0.7)
					(thickness 0.15)
				)
				(justify left bottom mirror)
			)
		)
		(property "Datasheet" "https://assets.nexperia.com/documents/data-sheet/BSS138PW.pdf"
			(at 0 0 180)
			(layer "F.Fab")
			(hide yes)
			(effects
				(font
					(size 1.27 1.27)
					(thickness 0.15)
				)
			)
		)
		(property "Description" "Power MOSFET, N Channel, 60 V, 320 mA, 0.9 ohm, SOT-323, Surface Mount"
			(at 0 0 180)
			(layer "F.Fab")
			(hide yes)
			(effects
				(font
					(size 1.27 1.27)
					(thickness 0.15)
				)
			)
		)
		(property "Author" "Antmicro"
			(at 163.15 164.15 0)
			(layer "B.Fab")
			(hide yes)
			(effects
				(font
					(size 1 1)
					(thickness 0.15)
				)
				(justify mirror)
			)
		)
		(property "License" "Apache-2.0"
			(at 163.15 164.15 0)
			(layer "B.Fab")
			(hide yes)
			(effects
				(font
					(size 1 1)
					(thickness 0.15)
				)
				(justify mirror)
			)
		)
		(property "MPN" "BSS138PW"
			(at 163.15 164.15 0)
			(layer "B.Fab")
			(hide yes)
			(effects
				(font
					(size 1 1)
					(thickness 0.15)
				)
				(justify mirror)
			)
		)
		(property "Manufacturer" "Nexperia"
			(at 163.15 164.15 0)
			(layer "B.Fab")
			(hide yes)
			(effects
				(font
					(size 1 1)
					(thickness 0.15)
				)
				(justify mirror)
			)
		)
		(sheetname "/Power supply/")
		(sheetfile "power-supply.kicad_sch")
		(attr smd)
		(fp_line
			(start 0.627 0.6)
			(end 0.627 0.999)
			(stroke
				(width 0.15)
				(type solid)
			)
			(layer "B.SilkS")
		)
		(fp_line
			(start 0.627 -0.6)
			(end 0.627 -1.001)
			(stroke
				(width 0.15)
				(type solid)
			)
			(layer "B.SilkS")
		)
		(fp_line
			(start -0.3 1)
			(end 0.627 0.999)
			(stroke
				(width 0.15)
				(type solid)
			)
			(layer "B.SilkS")
		)
		(fp_line
			(start -0.3 -1)
			(end 0.627 -1.001)
			(stroke
				(width 0.15)
				(type solid)
			)
			(layer "B.SilkS")
		)
		(fp_line
			(start 1.4 0.4)
			(end 1.4 -0.4)
			(stroke
				(width 0.05)
				(type solid)
			)
			(layer "B.CrtYd")
		)
		(fp_line
			(start 1.4 -0.4)
			(end 0.9 -0.4)
			(stroke
				(width 0.05)
				(type solid)
			)
			(layer "B.CrtYd")
		)
		(fp_line
			(start 0.9 1.3)
			(end 0.9 0.4)
			(stroke
				(width 0.05)
				(type solid)
			)
			(layer "B.CrtYd")
		)
		(fp_line
			(start 0.9 0.4)
			(end 1.4 0.4)
			(stroke
				(width 0.05)
				(type solid)
			)
			(layer "B.CrtYd")
		)
		(fp_line
			(start 0.9 -0.4)
			(end 0.9 -1.3)
			(stroke
				(width 0.05)
				(type solid)
			)
			(layer "B.CrtYd")
		)
		(fp_line
			(start 0.9 -1.3)
			(end -0.9 -1.3)
			(stroke
				(width 0.05)
				(type solid)
			)
			(layer "B.CrtYd")
		)
		(fp_line
			(start -0.9 1.3)
			(end 0.9 1.3)
			(stroke
				(width 0.05)
				(type solid)
			)
			(layer "B.CrtYd")
		)
		(fp_line
			(start -0.9 1.3)
			(end -0.9 1)
			(stroke
				(width 0.05)
				(type solid)
			)
			(layer "B.CrtYd")
		)
		(fp_line
			(start -0.9 1)
			(end -1.4 1)
			(stroke
				(width 0.05)
				(type solid)
			)
			(layer "B.CrtYd")
		)
		(fp_line
			(start -0.9 -1)
			(end -1.4 -1)
			(stroke
				(width 0.05)
				(type solid)
			)
			(layer "B.CrtYd")
		)
		(fp_line
			(start -0.9 -1.3)
			(end -0.9 -1)
			(stroke
				(width 0.05)
				(type solid)
			)
			(layer "B.CrtYd")
		)
		(fp_line
			(start -1.4 -1)
			(end -1.4 1)
			(stroke
				(width 0.05)
				(type solid)
			)
			(layer "B.CrtYd")
		)
		(fp_rect
			(start -0.623 0.999)
			(end 0.627 -1.001)
			(stroke
				(width 0.15)
				(type solid)
			)
			(fill no)
			(layer "B.Fab")
		)
		(pad "1" smd rect
			(at -1.051 0.65 90)
			(size 0.6 0.6)
			(layers "B.Cu" "B.Mask" "B.Paste")
			(net 538 "1V0_PG")
			(pinfunction "G")
			(pintype "input")
		)
		(pad "2" smd rect
			(at -1.051 -0.65 90)
			(size 0.6 0.6)
			(layers "B.Cu" "B.Mask" "B.Paste")
			(net 1 "GND")
			(pinfunction "S")
			(pintype "passive")
		)
		(pad "3" smd rect
			(at 1.05 0 90)
			(size 0.6 0.6)
			(layers "B.Cu" "B.Mask" "B.Paste")
			(net 207 "Net-(D4-C)")
			(pinfunction "D")
			(pintype "passive")
		)
	)
)
